(kicad_pcb
	(version 20241229)
	(generator "pcbnew")
	(generator_version "9.0")
	(general
		(thickness 1.62)
		(legacy_teardrops no)
	)
	(paper "A3")
	(title_block
		(title "COM Express 7 Baseboard")
		(date "2025-02-04")
		(rev "1.1.2")
		(company "Antmicro Ltd")
		(comment 1 "www.antmicro.com")
		(comment 9 "footprints 215-219 of 802")
	)
	(layers
		(0 "F.Cu" signal)
		(4 "In1.Cu" signal)
		(6 "In2.Cu" signal)
		(8 "In3.Cu" signal)
		(10 "In4.Cu" signal)
		(12 "In5.Cu" signal)
		(14 "In6.Cu" signal)
		(2 "B.Cu" signal)
		(9 "F.Adhes" user "F.Adhesive")
		(11 "B.Adhes" user "B.Adhesive")
		(13 "F.Paste" user)
		(15 "B.Paste" user)
		(5 "F.SilkS" user "F.Silkscreen")
		(7 "B.SilkS" user "B.Silkscreen")
		(1 "F.Mask" user)
		(3 "B.Mask" user)
		(17 "Dwgs.User" user "User.Drawings")
		(19 "Cmts.User" user "User.Comments")
		(21 "Eco1.User" user "User.Eco1")
		(23 "Eco2.User" user "User.Eco2")
		(25 "Edge.Cuts" user)
		(27 "Margin" user)
		(31 "F.CrtYd" user "F.Courtyard")
		(29 "B.CrtYd" user "B.Courtyard")
		(35 "F.Fab" user)
		(33 "B.Fab" user)
	)
	(footprint "antmicro-footprints:SOT-563"
		(layer "F.Cu")
		(at 312.425499 134.21 -90)
		(property "Reference" "U22"
			(at -3.65 -3.674501 180)
			(layer "F.SilkS")
			(effects
				(font
					(size 0.7 0.7)
					(thickness 0.15)
				)
				(justify right bottom)
			)
		)
		(property "Value" "TPS564247DRLR"
			(at 0 2.000001 90)
			(layer "F.Fab")
			(effects
				(font
					(size 0.7 0.7)
					(thickness 0.15)
				)
				(justify right bottom)
			)
		)
		(property "Datasheet" "https://www.ti.com/lit/ds/symlink/tps564247.pdf?ts=1713526387938&ref_url=https%253A%252F%252Fwww.mouser.pl%252F"
			(at 0 0 270)
			(layer "F.Fab")
			(hide yes)
			(effects
				(font
					(size 1.27 1.27)
					(thickness 0.15)
				)
			)
		)
		(property "Author" "Antmicro"
			(at 178.215499 446.635499 0)
			(layer "F.Fab")
			(hide yes)
			(effects
				(font
					(size 1 1)
					(thickness 0.15)
				)
			)
		)
		(property "License" "Apache-2.0"
			(at 178.215499 446.635499 0)
			(layer "F.Fab")
			(hide yes)
			(effects
				(font
					(size 1 1)
					(thickness 0.15)
				)
			)
		)
		(property "MPN" "TPS564247DRLR"
			(at 178.215499 446.635499 0)
			(layer "F.Fab")
			(hide yes)
			(effects
				(font
					(size 1 1)
					(thickness 0.15)
				)
			)
		)
		(property "Manufacturer" "Texas Instruments"
			(at 178.215499 446.635499 0)
			(layer "F.Fab")
			(hide yes)
			(effects
				(font
					(size 1 1)
					(thickness 0.15)
				)
			)
		)
		(sheetname "Power")
		(sheetfile "power.kicad_sch")
		(attr smd)
		(fp_line
			(start 0.776 0.972)
			(end 0.526 0.972)
			(stroke
				(width 0.15)
				(type solid)
			)
			(layer "F.SilkS")
		)
		(fp_line
			(start -0.778 0.949)
			(end -0.424 0.949)
			(stroke
				(width 0.15)
				(type solid)
			)
			(layer "F.SilkS")
		)
		(fp_line
			(start -0.778 0.776)
			(end -0.778 0.949)
			(stroke
				(width 0.15)
				(type solid)
			)
			(layer "F.SilkS")
		)
		(fp_line
			(start 0.776 0.776)
			(end 0.776 0.972)
			(stroke
				(width 0.15)
				(type solid)
			)
			(layer "F.SilkS")
		)
		(fp_line
			(start -0.499 -0.974)
			(end -0.724 -0.778)
			(stroke
				(width 0.15)
				(type solid)
			)
			(layer "F.SilkS")
		)
		(fp_line
			(start 0.776 -0.974)
			(end 0.776 -0.778)
			(stroke
				(width 0.15)
				(type solid)
			)
			(layer "F.SilkS")
		)
		(fp_line
			(start 0.776 -0.974)
			(end 0.526 -0.974)
			(stroke
				(width 0.15)
				(type solid)
			)
			(layer "F.SilkS")
		)
		(fp_circle
			(center -0.903 -0.999)
			(end -0.952 -0.95)
			(stroke
				(width 0.15)
				(type solid)
			)
			(fill yes)
			(layer "F.SilkS")
		)
		(fp_rect
			(start 1.19 -1.12)
			(end -1.2 1.1)
			(stroke
				(width 0.05)
				(type solid)
			)
			(fill no)
			(layer "F.CrtYd")
		)
		(fp_line
			(start 0.651 0.847)
			(end -0.653 0.847)
			(stroke
				(width 0.15)
				(type solid)
			)
			(layer "F.Fab")
		)
		(fp_line
			(start -0.653 -0.678)
			(end -0.653 0.847)
			(stroke
				(width 0.15)
				(type solid)
			)
			(layer "F.Fab")
		)
		(fp_line
			(start -0.453 -0.849)
			(end -0.653 -0.678)
			(stroke
				(width 0.15)
				(type solid)
			)
			(layer "F.Fab")
		)
		(fp_line
			(start -0.453 -0.849)
			(end 0.651 -0.849)
			(stroke
				(width 0.15)
				(type solid)
			)
			(layer "F.Fab")
		)
		(fp_line
			(start 0.651 -0.849)
			(end 0.651 0.847)
			(stroke
				(width 0.15)
				(type solid)
			)
			(layer "F.Fab")
		)
		(pad "1" smd roundrect
			(at -0.749 -0.499 180)
			(size 0.3 0.6)
			(layers "F.Cu" "F.Mask" "F.Paste")
			(roundrect_rratio 0.25)
			(net 62 "+12V_AON")
			(pinfunction "V_{IN}")
			(pintype "power_in")
			(teardrops
				(best_length_ratio 0.2)
				(max_length 1)
				(best_width_ratio 0.9)
				(max_width 2)
				(curved_edges yes)
				(filter_ratio 0.9)
				(enabled yes)
				(allow_two_segments yes)
				(prefer_zone_connections yes)
			)
		)
		(pad "2" smd roundrect
			(at -0.749 0.001 180)
			(size 0.3 0.6)
			(layers "F.Cu" "F.Mask" "F.Paste")
			(roundrect_rratio 0.25)
			(net 871 "Net-(U22-SW)")
			(pinfunction "SW")
			(pintype "passive")
			(teardrops
				(best_length_ratio 0.2)
				(max_length 1)
				(best_width_ratio 0.9)
				(max_width 2)
				(curved_edges yes)
				(filter_ratio 0.9)
				(enabled yes)
				(allow_two_segments yes)
				(prefer_zone_connections yes)
			)
		)
		(pad "3" smd roundrect
			(at -0.749 0.497 180)
			(size 0.3 0.6)
			(layers "F.Cu" "F.Mask" "F.Paste")
			(roundrect_rratio 0.25)
			(net 1 "GND")
			(pinfunction "GND")
			(pintype "power_in")
			(teardrops
				(best_length_ratio 0.2)
				(max_length 1)
				(best_width_ratio 0.9)
				(max_width 2)
				(curved_edges yes)
				(filter_ratio 0.9)
				(enabled yes)
				(allow_two_segments yes)
				(prefer_zone_connections yes)
			)
		)
		(pad "4" smd roundrect
			(at 0.747 0.497 180)
			(size 0.3 0.6)
			(layers "F.Cu" "F.Mask" "F.Paste")
			(roundrect_rratio 0.25)
			(net 1 "GND")
			(pinfunction "AGND")
			(pintype "power_in")
			(teardrops
				(best_length_ratio 0.2)
				(max_length 1)
				(best_width_ratio 0.9)
				(max_width 2)
				(curved_edges yes)
				(filter_ratio 0.9)
				(enabled yes)
				(allow_two_segments yes)
				(prefer_zone_connections yes)
			)
		)
		(pad "5" smd roundrect
			(at 0.747 0.001 180)
			(size 0.3 0.6)
			(layers "F.Cu" "F.Mask" "F.Paste")
			(roundrect_rratio 0.25)
			(net 583 "Net-(U22-EN)")
			(pinfunction "EN")
			(pintype "passive")
			(teardrops
				(best_length_ratio 0.2)
				(max_length 1)
				(best_width_ratio 0.9)
				(max_width 2)
				(curved_edges yes)
				(filter_ratio 0.9)
				(enabled yes)
				(allow_two_segments yes)
				(prefer_zone_connections yes)
			)
		)
		(pad "6" smd roundrect
			(at 0.747 -0.499 180)
			(size 0.3 0.6)
			(layers "F.Cu" "F.Mask" "F.Paste")
			(roundrect_rratio 0.25)
			(net 586 "Net-(U22-FB)")
			(pinfunction "FB")
			(pintype "passive")
			(teardrops
				(best_length_ratio 0.2)
				(max_length 1)
				(best_width_ratio 0.9)
				(max_width 2)
				(curved_edges yes)
				(filter_ratio 0.9)
				(enabled yes)
				(allow_two_segments yes)
				(prefer_zone_connections yes)
			)
		)
	)
	(footprint "antmicro-footprints:R_0402_1005Metric"
		(layer "F.Cu")
		(at 302.575 138.285 90)
		(descr "Resistor SMD 0402")
		(tags "resistor SMD 0402")
		(property "Reference" "R90"
			(at -0.825 -0.525 90)
			(layer "F.SilkS")
			(effects
				(font
					(size 0.7 0.7)
					(thickness 0.15)
				)
				(justify left bottom)
			)
		)
		(property "Value" "R_100k_0402"
			(at -1.011843 1.772047 90)
			(layer "F.Fab")
			(effects
				(font
					(size 0.7 0.7)
					(thickness 0.15)
				)
				(justify left bottom)
			)
		)
		(property "Datasheet" "https://www.bourns.com/docs/product-datasheets/cr.pdf"
			(at 0 0 90)
			(layer "F.Fab")
			(hide yes)
			(effects
				(font
					(size 1.27 1.27)
					(thickness 0.15)
				)
			)
		)
		(property "Author" "Antmicro"
			(at 440.86 -164.29 0)
			(layer "F.Fab")
			(hide yes)
			(effects
				(font
					(size 1 1)
					(thickness 0.15)
				)
			)
		)
		(property "License" "Apache-2.0"
			(at 440.86 -164.29 0)
			(layer "F.Fab")
			(hide yes)
			(effects
				(font
					(size 1 1)
					(thickness 0.15)
				)
			)
		)
		(property "MPN" "CR0402-FX-1003GLF"
			(at 440.86 -164.29 0)
			(layer "F.Fab")
			(hide yes)
			(effects
				(font
					(size 1 1)
					(thickness 0.15)
				)
			)
		)
		(property "Manufacturer" "Bourns"
			(at 440.86 -164.29 0)
			(layer "F.Fab")
			(hide yes)
			(effects
				(font
					(size 1 1)
					(thickness 0.15)
				)
			)
		)
		(property "Public" "False"
			(at 440.86 -164.29 0)
			(layer "F.Fab")
			(hide yes)
			(effects
				(font
					(size 1 1)
					(thickness 0.15)
				)
			)
		)
		(property "Tolerance" "1%"
			(at 440.86 -164.29 0)
			(layer "F.Fab")
			(hide yes)
			(effects
				(font
					(size 1 1)
					(thickness 0.15)
				)
			)
		)
		(property "Val" "100k"
			(at 440.86 -164.29 0)
			(layer "F.Fab")
			(hide yes)
			(effects
				(font
					(size 1 1)
					(thickness 0.15)
				)
			)
		)
		(sheetname "Power")
		(sheetfile "power.kicad_sch")
		(attr smd)
		(fp_rect
			(start -0.925 -0.47)
			(end 0.925 0.47)
			(stroke
				(width 0.05)
				(type default)
			)
			(fill no)
			(layer "F.CrtYd")
		)
		(fp_rect
			(start -0.5 -0.25)
			(end 0.5 0.25)
			(stroke
				(width 0.15)
				(type solid)
			)
			(fill no)
			(layer "F.Fab")
		)
		(pad "1" smd roundrect
			(at -0.48 0 90)
			(size 0.59 0.64)
			(layers "F.Cu" "F.Mask" "F.Paste")
			(roundrect_rratio 0.25)
			(net 1 "GND")
			(pintype "passive")
			(teardrops
				(best_length_ratio 0.2)
				(max_length 1)
				(best_width_ratio 0.9)
				(max_width 2)
				(curved_edges yes)
				(filter_ratio 0.9)
				(enabled yes)
				(allow_two_segments yes)
				(prefer_zone_connections yes)
			)
		)
		(pad "2" smd roundrect
			(at 0.48 0 90)
			(size 0.59 0.64)
			(layers "F.Cu" "F.Mask" "F.Paste")
			(roundrect_rratio 0.25)
			(net 533 "/Com Express 7 MGMT/PSON")
			(pintype "passive")
			(teardrops
				(best_length_ratio 0.2)
				(max_length 1)
				(best_width_ratio 0.9)
				(max_width 2)
				(curved_edges yes)
				(filter_ratio 0.9)
				(enabled yes)
				(allow_two_segments yes)
				(prefer_zone_connections yes)
			)
		)
	)
	(footprint "antmicro-footprints:R_0402_1005Metric"
		(layer "F.Cu")
		(at 155.299 167.36 180)
		(descr "Resistor SMD 0402")
		(tags "resistor SMD 0402")
		(property "Reference" "R62"
			(at -4.551 18.1 0)
			(layer "F.SilkS")
			(effects
				(font
					(size 0.7 0.7)
					(thickness 0.15)
				)
				(justify left bottom)
			)
		)
		(property "Value" "R_220R_0402"
			(at -1.011843 1.772047 0)
			(layer "F.Fab")
			(effects
				(font
					(size 0.7 0.7)
					(thickness 0.15)
				)
				(justify right bottom)
			)
		)
		(property "Datasheet" "https://www.bourns.com/docs/product-datasheets/cr.pdf"
			(at 0 0 180)
			(layer "F.Fab")
			(hide yes)
			(effects
				(font
					(size 1.27 1.27)
					(thickness 0.15)
				)
			)
		)
		(property "Author" "Antmicro"
			(at 310.598 334.72 0)
			(layer "F.Fab")
			(hide yes)
			(effects
				(font
					(size 1 1)
					(thickness 0.15)
				)
			)
		)
		(property "License" "Apache-2.0"
			(at 310.598 334.72 0)
			(layer "F.Fab")
			(hide yes)
			(effects
				(font
					(size 1 1)
					(thickness 0.15)
				)
			)
		)
		(property "MPN" "CR0402-FX-2200GLF"
			(at 310.598 334.72 0)
			(layer "F.Fab")
			(hide yes)
			(effects
				(font
					(size 1 1)
					(thickness 0.15)
				)
			)
		)
		(property "Manufacturer" "Bourns"
			(at 310.598 334.72 0)
			(layer "F.Fab")
			(hide yes)
			(effects
				(font
					(size 1 1)
					(thickness 0.15)
				)
			)
		)
		(property "Public" "False"
			(at 310.598 334.72 0)
			(layer "F.Fab")
			(hide yes)
			(effects
				(font
					(size 1 1)
					(thickness 0.15)
				)
			)
		)
		(property "Tolerance" "1%"
			(at 310.598 334.72 0)
			(layer "F.Fab")
			(hide yes)
			(effects
				(font
					(size 1 1)
					(thickness 0.15)
				)
			)
		)
		(property "Val" "220R"
			(at 310.598 334.72 0)
			(layer "F.Fab")
			(hide yes)
			(effects
				(font
					(size 1 1)
					(thickness 0.15)
				)
			)
		)
		(sheetname "2xSFP+")
		(sheetfile "2xSFP+.kicad_sch")
		(attr smd)
		(fp_rect
			(start -0.925 -0.47)
			(end 0.925 0.47)
			(stroke
				(width 0.05)
				(type default)
			)
			(fill no)
			(layer "F.CrtYd")
		)
		(fp_rect
			(start -0.5 -0.25)
			(end 0.5 0.25)
			(stroke
				(width 0.15)
				(type solid)
			)
			(fill no)
			(layer "F.Fab")
		)
		(pad "1" smd roundrect
			(at -0.48 0 180)
			(size 0.59 0.64)
			(layers "F.Cu" "F.Mask" "F.Paste")
			(roundrect_rratio 0.25)
			(net 898 "/2xSFP+/SFP1_LEDY")
			(pintype "passive")
			(teardrops
				(best_length_ratio 0.2)
				(max_length 1)
				(best_width_ratio 0.9)
				(max_width 2)
				(curved_edges yes)
				(filter_ratio 0.9)
				(enabled yes)
				(allow_two_segments yes)
				(prefer_zone_connections yes)
			)
		)
		(pad "2" smd roundrect
			(at 0.48 0 180)
			(size 0.59 0.64)
			(layers "F.Cu" "F.Mask" "F.Paste")
			(roundrect_rratio 0.25)
			(net 930 "Net-(D5-C)")
			(pintype "passive")
			(teardrops
				(best_length_ratio 0.2)
				(max_length 1)
				(best_width_ratio 0.9)
				(max_width 2)
				(curved_edges yes)
				(filter_ratio 0.9)
				(enabled yes)
				(allow_two_segments yes)
				(prefer_zone_connections yes)
			)
		)
	)
	(footprint "antmicro-footprints:R_0402_1005Metric"
		(layer "F.Cu")
		(at 127.9 81.760001 -90)
		(descr "Resistor SMD 0402")
		(tags "resistor SMD 0402")
		(property "Reference" "R236"
			(at -3.650001 -0.45 90)
			(layer "F.SilkS")
			(effects
				(font
					(size 0.7 0.7)
					(thickness 0.15)
				)
				(justify right bottom)
			)
		)
		(property "Value" "R_0R_0402"
			(at -1.011843 1.772047 90)
			(layer "F.Fab")
			(effects
				(font
					(size 0.7 0.7)
					(thickness 0.15)
				)
				(justify right bottom)
			)
		)
		(property "Datasheet" "https://industrial.panasonic.com/cdbs/www-data/pdf/RDA0000/AOA0000C301.pdf"
			(at 0 0 270)
			(layer "F.Fab")
			(hide yes)
			(effects
				(font
					(size 1.27 1.27)
					(thickness 0.15)
				)
			)
		)
		(property "Author" "Antmicro"
			(at 46.139999 209.660001 0)
			(layer "F.Fab")
			(hide yes)
			(effects
				(font
					(size 1 1)
					(thickness 0.15)
				)
			)
		)
		(property "Current" "1A"
			(at 46.139999 209.660001 0)
			(layer "F.Fab")
			(hide yes)
			(effects
				(font
					(size 1 1)
					(thickness 0.15)
				)
			)
		)
		(property "License" "Apache-2.0"
			(at 46.139999 209.660001 0)
			(layer "F.Fab")
			(hide yes)
			(effects
				(font
					(size 1 1)
					(thickness 0.15)
				)
			)
		)
		(property "MPN" "ERJ2GE0R00X"
			(at 46.139999 209.660001 0)
			(layer "F.Fab")
			(hide yes)
			(effects
				(font
					(size 1 1)
					(thickness 0.15)
				)
			)
		)
		(property "Manufacturer" "Panasonic"
			(at 46.139999 209.660001 0)
			(layer "F.Fab")
			(hide yes)
			(effects
				(font
					(size 1 1)
					(thickness 0.15)
				)
			)
		)
		(property "Public" "False"
			(at 46.139999 209.660001 0)
			(layer "F.Fab")
			(hide yes)
			(effects
				(font
					(size 1 1)
					(thickness 0.15)
				)
			)
		)
		(property "Tolerance" ""
			(at 46.139999 209.660001 0)
			(layer "F.Fab")
			(hide yes)
			(effects
				(font
					(size 1 1)
					(thickness 0.15)
				)
			)
		)
		(property "Val" "0R"
			(at 46.139999 209.660001 0)
			(layer "F.Fab")
			(hide yes)
			(effects
				(font
					(size 1 1)
					(thickness 0.15)
				)
			)
		)
		(sheetname "GPIO expander")
		(sheetfile "gpio_exp.kicad_sch")
		(attr smd)
		(fp_rect
			(start -0.925 -0.47)
			(end 0.925 0.47)
			(stroke
				(width 0.05)
				(type default)
			)
			(fill no)
			(layer "F.CrtYd")
		)
		(fp_rect
			(start -0.5 -0.25)
			(end 0.5 0.25)
			(stroke
				(width 0.15)
				(type solid)
			)
			(fill no)
			(layer "F.Fab")
		)
		(pad "1" smd roundrect
			(at -0.48 0 270)
			(size 0.59 0.64)
			(layers "F.Cu" "F.Mask" "F.Paste")
			(roundrect_rratio 0.25)
			(net 528 "/Backplane/~{PERST}")
			(pintype "passive")
			(teardrops
				(best_length_ratio 0.2)
				(max_length 1)
				(best_width_ratio 0.9)
				(max_width 2)
				(curved_edges yes)
				(filter_ratio 0.9)
				(enabled yes)
				(allow_two_segments yes)
				(prefer_zone_connections yes)
			)
		)
		(pad "2" smd roundrect
			(at 0.48 0 270)
			(size 0.59 0.64)
			(layers "F.Cu" "F.Mask" "F.Paste")
			(roundrect_rratio 0.25)
			(net 637 "Net-(U41-~{RESET})")
			(pintype "passive")
			(teardrops
				(best_length_ratio 0.2)
				(max_length 1)
				(best_width_ratio 0.9)
				(max_width 2)
				(curved_edges yes)
				(filter_ratio 0.9)
				(enabled yes)
				(allow_two_segments yes)
				(prefer_zone_connections yes)
			)
		)
	)
	(footprint "antmicro-footprints:R_0402_1005Metric"
		(layer "F.Cu")
		(at 155.299 163.11 180)
		(descr "Resistor SMD 0402")
		(tags "resistor SMD 0402")
		(property "Reference" "R48"
			(at -6.701 17.5 0)
			(layer "F.SilkS")
			(effects
				(font
					(size 0.7 0.7)
					(thickness 0.15)
				)
				(justify right bottom)
			)
		)
		(property "Value" "R_0R_0402"
			(at -1.011843 1.772047 0)
			(layer "F.Fab")
			(effects
				(font
					(size 0.7 0.7)
					(thickness 0.15)
				)
				(justify right bottom)
			)
		)
		(property "Datasheet" "https://industrial.panasonic.com/cdbs/www-data/pdf/RDA0000/AOA0000C301.pdf"
			(at 0 0 180)
			(layer "F.Fab")
			(hide yes)
			(effects
				(font
					(size 1.27 1.27)
					(thickness 0.15)
				)
			)
		)
		(property "Author" "Antmicro"
			(at 310.598 326.22 0)
			(layer "F.Fab")
			(hide yes)
			(effects
				(font
					(size 1 1)
					(thickness 0.15)
				)
			)
		)
		(property "Current" "1A"
			(at 310.598 326.22 0)
			(layer "F.Fab")
			(hide yes)
			(effects
				(font
					(size 1 1)
					(thickness 0.15)
				)
			)
		)
		(property "License" "Apache-2.0"
			(at 310.598 326.22 0)
			(layer "F.Fab")
			(hide yes)
			(effects
				(font
					(size 1 1)
					(thickness 0.15)
				)
			)
		)
		(property "MPN" "ERJ2GE0R00X"
			(at 310.598 326.22 0)
			(layer "F.Fab")
			(hide yes)
			(effects
				(font
					(size 1 1)
					(thickness 0.15)
				)
			)
		)
		(property "Manufacturer" "Panasonic"
			(at 310.598 326.22 0)
			(layer "F.Fab")
			(hide yes)
			(effects
				(font
					(size 1 1)
					(thickness 0.15)
				)
			)
		)
		(property "Public" "False"
			(at 310.598 326.22 0)
			(layer "F.Fab")
			(hide yes)
			(effects
				(font
					(size 1 1)
					(thickness 0.15)
				)
			)
		)
		(property "Tolerance" ""
			(at 310.598 326.22 0)
			(layer "F.Fab")
			(hide yes)
			(effects
				(font
					(size 1 1)
					(thickness 0.15)
				)
			)
		)
		(property "Val" "0R"
			(at 310.598 326.22 0)
			(layer "F.Fab")
			(hide yes)
			(effects
				(font
					(size 1 1)
					(thickness 0.15)
				)
			)
		)
		(sheetname "2xSFP+")
		(sheetfile "2xSFP+.kicad_sch")
		(attr smd dnp)
		(fp_rect
			(start -0.925 -0.47)
			(end 0.925 0.47)
			(stroke
				(width 0.05)
				(type default)
			)
			(fill no)
			(layer "F.CrtYd")
		)
		(fp_rect
			(start -0.5 -0.25)
			(end 0.5 0.25)
			(stroke
				(width 0.15)
				(type solid)
			)
			(fill no)
			(layer "F.Fab")
		)
		(pad "1" smd roundrect
			(at -0.48 0 180)
			(size 0.59 0.64)
			(layers "F.Cu" "F.Mask" "F.Paste")
			(roundrect_rratio 0.25)
			(net 567 "/2xSFP+/~{LED1_2}")
			(pintype "passive")
			(teardrops
				(best_length_ratio 0.2)
				(max_length 1)
				(best_width_ratio 0.9)
				(max_width 2)
				(curved_edges yes)
				(filter_ratio 0.9)
				(enabled yes)
				(allow_two_segments yes)
				(prefer_zone_connections yes)
			)
		)
		(pad "2" smd roundrect
			(at 0.48 0 180)
			(size 0.59 0.64)
			(layers "F.Cu" "F.Mask" "F.Paste")
			(roundrect_rratio 0.25)
			(net 929 "/2xSFP+/SFP1_LEDG")
			(pintype "passive")
			(teardrops
				(best_length_ratio 0.2)
				(max_length 1)
				(best_width_ratio 0.9)
				(max_width 2)
				(curved_edges yes)
				(filter_ratio 0.9)
				(enabled yes)
				(allow_two_segments yes)
				(prefer_zone_connections yes)
			)
		)
	)
)
